(kicad_pcb
	(version 20260206)
	(generator "pcbnew")
	(generator_version "10.0")
	(general
		(thickness 1.6)
		(legacy_teardrops no)
	)
	(paper "A4")
	(title_block
		(title "03242023_DA0F0TMBIJ0_F0T_Motherboard_J_brd_V01_OCP.brd")
		(comment 1 "Grand Teton / footprint 1690 of 6105 (J16), pads 1-112 of 291")
	)
	(layers
		(0 "F.Cu" signal "TOP")
		(4 "In1.Cu" signal "GND")
		(6 "In2.Cu" signal "IN1")
		(8 "In3.Cu" signal "GND1")
		(10 "In4.Cu" signal "IN2")
		(12 "In5.Cu" signal "GND2")
		(14 "In6.Cu" signal "IN3")
		(16 "In7.Cu" signal "GND3")
		(18 "In8.Cu" signal "VCC")
		(20 "In9.Cu" signal "VCC1")
		(22 "In10.Cu" signal "GND4")
		(24 "In11.Cu" signal "IN4")
		(26 "In12.Cu" signal "GND5")
		(28 "In13.Cu" signal "IN5")
		(30 "In14.Cu" signal "GND6")
		(32 "In15.Cu" signal "IN6")
		(34 "In16.Cu" signal "GND7")
		(2 "B.Cu" signal "BOTTOM")
		(9 "F.Adhes" user "F.Adhesive")
		(11 "B.Adhes" user "B.Adhesive")
		(13 "F.Paste" user "Package Geometry/Pastemask Top")
		(15 "B.Paste" user "Package Geometry/Pastemask Bottom")
		(5 "F.SilkS" user "Ref Des/Silkscreen Top")
		(7 "B.SilkS" user "Ref Des/Silkscreen Bottom")
		(1 "F.Mask" user "Board Geometry/Soldermask Top")
		(3 "B.Mask" user "Board Geometry/Soldermask Bottom")
		(17 "Dwgs.User" user "User.Drawings")
		(19 "Cmts.User" user "User.Comments")
		(21 "Eco1.User" user "User.Eco1")
		(23 "Eco2.User" user "User.Eco2")
		(25 "Edge.Cuts" user "Board Geometry/Outline")
		(27 "Margin" user)
		(31 "F.CrtYd" user "Package Geometry/Place Bound Top")
		(29 "B.CrtYd" user "Package Geometry/Place Bound Bottom")
		(35 "F.Fab" user "Ref Des/Assembly Top")
		(33 "B.Fab" user "Ref Des/Assembly Bottom")
	)
	(footprint ""
		(layer "F.Cu")
		(at 454.066148 -258.091686)
		(property "Reference" "J16"
			(at -0.279908 -81.779872 0)
			(unlocked yes)
			(layer "F.SilkS")
			(effects
				(font
					(size 0.7874 0.5842)
					(thickness 0.1524)
				)
				(justify left)
			)
		)
		(property "Value" ""
			(at 0 0 0)
			(layer "F.Fab")
			(effects
				(font
					(size 1.27 1.27)
				)
			)
		)
		(duplicate_pad_numbers_are_jumpers no)
		(pad "1" smd rect
			(at -2.050034 -63.324994 270)
			(size 0.519938 1.4986)
			(layers "F.Cu" "F.Mask" "F.Paste")
			(net "P12V_S3_AUX_CPU0_NVDIMM")
		)
		(pad "2" smd rect
			(at -2.050034 -62.47511 270)
			(size 0.519938 1.4986)
			(layers "F.Cu" "F.Mask" "F.Paste")
			(net "TP_CHH_CPU0_DIMM2_FRU_0")
		)
		(pad "3" smd rect
			(at -2.050034 -61.624972 270)
			(size 0.519938 1.4986)
			(layers "F.Cu" "F.Mask" "F.Paste")
			(net "P3V3_AUX")
		)
		(pad "4" smd rect
			(at -2.050034 -60.775088 270)
			(size 0.519938 1.4986)
			(layers "F.Cu" "F.Mask" "F.Paste")
			(net "I3C_SPD_DDREFGH_CPU0_LVC1_SCL_7")
		)
		(pad "5" smd rect
			(at -2.050034 -59.92495 270)
			(size 0.519938 1.4986)
			(layers "F.Cu" "F.Mask" "F.Paste")
			(net "I3C_SPD_DDREFGH_CPU0_LVC1_SDA")
		)
		(pad "6" smd rect
			(at -2.050034 -59.075066 270)
			(size 0.519938 1.4986)
			(layers "F.Cu" "F.Mask" "F.Paste")
			(net "GND")
		)
		(pad "7" smd rect
			(at -2.050034 -58.224928 270)
			(size 0.519938 1.4986)
			(layers "F.Cu" "F.Mask" "F.Paste")
			(net "M_H_CPU0_SA_DQ<0>")
		)
		(pad "8" smd rect
			(at -2.050034 -57.375044 270)
			(size 0.519938 1.4986)
			(layers "F.Cu" "F.Mask" "F.Paste")
			(net "GND")
		)
		(pad "9" smd rect
			(at -2.050034 -56.524906 270)
			(size 0.519938 1.4986)
			(layers "F.Cu" "F.Mask" "F.Paste")
			(net "M_H_CPU0_SA_DQ<1>")
		)
		(pad "10" smd rect
			(at -2.050034 -55.675022 270)
			(size 0.519938 1.4986)
			(layers "F.Cu" "F.Mask" "F.Paste")
			(net "GND")
		)
		(pad "11" smd rect
			(at -2.050034 -54.824884 270)
			(size 0.519938 1.4986)
			(layers "F.Cu" "F.Mask" "F.Paste")
			(net "M_H_CPU0_SA_DQS_DP<0>")
		)
		(pad "12" smd rect
			(at -2.050034 -53.975 270)
			(size 0.519938 1.4986)
			(layers "F.Cu" "F.Mask" "F.Paste")
			(net "M_H_CPU0_SA_DQS_DN<0>")
		)
		(pad "13" smd rect
			(at -2.050034 -53.125116 270)
			(size 0.519938 1.4986)
			(layers "F.Cu" "F.Mask" "F.Paste")
			(net "GND")
		)
		(pad "14" smd rect
			(at -2.050034 -52.274978 270)
			(size 0.519938 1.4986)
			(layers "F.Cu" "F.Mask" "F.Paste")
			(net "M_H_CPU0_SA_DQ<4>")
		)
		(pad "15" smd rect
			(at -2.050034 -51.425094 270)
			(size 0.519938 1.4986)
			(layers "F.Cu" "F.Mask" "F.Paste")
			(net "GND")
		)
		(pad "16" smd rect
			(at -2.050034 -50.574956 270)
			(size 0.519938 1.4986)
			(layers "F.Cu" "F.Mask" "F.Paste")
			(net "M_H_CPU0_SA_DQ<5>")
		)
		(pad "17" smd rect
			(at -2.050034 -49.725072 270)
			(size 0.519938 1.4986)
			(layers "F.Cu" "F.Mask" "F.Paste")
			(net "GND")
		)
		(pad "18" smd rect
			(at -2.050034 -48.874934 270)
			(size 0.519938 1.4986)
			(layers "F.Cu" "F.Mask" "F.Paste")
			(net "M_H_CPU0_SA_DQ<8>")
		)
		(pad "19" smd rect
			(at -2.050034 -48.02505 270)
			(size 0.519938 1.4986)
			(layers "F.Cu" "F.Mask" "F.Paste")
			(net "GND")
		)
		(pad "20" smd rect
			(at -2.050034 -47.174912 270)
			(size 0.519938 1.4986)
			(layers "F.Cu" "F.Mask" "F.Paste")
			(net "M_H_CPU0_SA_DQ<9>")
		)
		(pad "21" smd rect
			(at -2.050034 -46.325028 270)
			(size 0.519938 1.4986)
			(layers "F.Cu" "F.Mask" "F.Paste")
			(net "GND")
		)
		(pad "22" smd rect
			(at -2.050034 -45.47489 270)
			(size 0.519938 1.4986)
			(layers "F.Cu" "F.Mask" "F.Paste")
			(net "M_H_CPU0_SA_DQS_DP<1>")
		)
		(pad "23" smd rect
			(at -2.050034 -44.625006 270)
			(size 0.519938 1.4986)
			(layers "F.Cu" "F.Mask" "F.Paste")
			(net "M_H_CPU0_SA_DQS_DN<1>")
		)
		(pad "24" smd rect
			(at -2.050034 -43.775122 270)
			(size 0.519938 1.4986)
			(layers "F.Cu" "F.Mask" "F.Paste")
			(net "GND")
		)
		(pad "25" smd rect
			(at -2.050034 -42.924984 270)
			(size 0.519938 1.4986)
			(layers "F.Cu" "F.Mask" "F.Paste")
			(net "M_H_CPU0_SA_DQ<12>")
		)
		(pad "26" smd rect
			(at -2.050034 -42.0751 270)
			(size 0.519938 1.4986)
			(layers "F.Cu" "F.Mask" "F.Paste")
			(net "GND")
		)
		(pad "27" smd rect
			(at -2.050034 -41.224962 270)
			(size 0.519938 1.4986)
			(layers "F.Cu" "F.Mask" "F.Paste")
			(net "M_H_CPU0_SA_DQ<13>")
		)
		(pad "28" smd rect
			(at -2.050034 -40.375078 270)
			(size 0.519938 1.4986)
			(layers "F.Cu" "F.Mask" "F.Paste")
			(net "GND")
		)
		(pad "29" smd rect
			(at -2.050034 -39.52494 270)
			(size 0.519938 1.4986)
			(layers "F.Cu" "F.Mask" "F.Paste")
			(net "M_H_CPU0_SA_DQ<16>")
		)
		(pad "30" smd rect
			(at -2.050034 -38.675056 270)
			(size 0.519938 1.4986)
			(layers "F.Cu" "F.Mask" "F.Paste")
			(net "GND")
		)
		(pad "31" smd rect
			(at -2.050034 -37.824918 270)
			(size 0.519938 1.4986)
			(layers "F.Cu" "F.Mask" "F.Paste")
			(net "M_H_CPU0_SA_DQ<17>")
		)
		(pad "32" smd rect
			(at -2.050034 -36.975034 270)
			(size 0.519938 1.4986)
			(layers "F.Cu" "F.Mask" "F.Paste")
			(net "GND")
		)
		(pad "33" smd rect
			(at -2.050034 -36.124896 270)
			(size 0.519938 1.4986)
			(layers "F.Cu" "F.Mask" "F.Paste")
			(net "M_H_CPU0_SA_DQS_DP<2>")
		)
		(pad "34" smd rect
			(at -2.050034 -35.275012 270)
			(size 0.519938 1.4986)
			(layers "F.Cu" "F.Mask" "F.Paste")
			(net "M_H_CPU0_SA_DQS_DN<2>")
		)
		(pad "35" smd rect
			(at -2.050034 -34.425128 270)
			(size 0.519938 1.4986)
			(layers "F.Cu" "F.Mask" "F.Paste")
			(net "GND")
		)
		(pad "36" smd rect
			(at -2.050034 -33.57499 270)
			(size 0.519938 1.4986)
			(layers "F.Cu" "F.Mask" "F.Paste")
			(net "M_H_CPU0_SA_DQ<20>")
		)
		(pad "37" smd rect
			(at -2.050034 -32.725106 270)
			(size 0.519938 1.4986)
			(layers "F.Cu" "F.Mask" "F.Paste")
			(net "GND")
		)
		(pad "38" smd rect
			(at -2.050034 -31.874968 270)
			(size 0.519938 1.4986)
			(layers "F.Cu" "F.Mask" "F.Paste")
			(net "M_H_CPU0_SA_DQ<21>")
		)
		(pad "39" smd rect
			(at -2.050034 -31.025084 270)
			(size 0.519938 1.4986)
			(layers "F.Cu" "F.Mask" "F.Paste")
			(net "GND")
		)
		(pad "40" smd rect
			(at -2.050034 -30.174946 270)
			(size 0.519938 1.4986)
			(layers "F.Cu" "F.Mask" "F.Paste")
			(net "M_H_CPU0_SA_DQ<24>")
		)
		(pad "41" smd rect
			(at -2.050034 -29.325062 270)
			(size 0.519938 1.4986)
			(layers "F.Cu" "F.Mask" "F.Paste")
			(net "GND")
		)
		(pad "42" smd rect
			(at -2.050034 -28.474924 270)
			(size 0.519938 1.4986)
			(layers "F.Cu" "F.Mask" "F.Paste")
			(net "M_H_CPU0_SA_DQ<25>")
		)
		(pad "43" smd rect
			(at -2.050034 -27.62504 270)
			(size 0.519938 1.4986)
			(layers "F.Cu" "F.Mask" "F.Paste")
			(net "GND")
		)
		(pad "44" smd rect
			(at -2.050034 -26.774902 270)
			(size 0.519938 1.4986)
			(layers "F.Cu" "F.Mask" "F.Paste")
			(net "M_H_CPU0_SA_DQS_DP<3>")
		)
		(pad "45" smd rect
			(at -2.050034 -25.925018 270)
			(size 0.519938 1.4986)
			(layers "F.Cu" "F.Mask" "F.Paste")
			(net "M_H_CPU0_SA_DQS_DN<3>")
		)
		(pad "46" smd rect
			(at -2.050034 -25.07488 270)
			(size 0.519938 1.4986)
			(layers "F.Cu" "F.Mask" "F.Paste")
			(net "GND")
		)
		(pad "47" smd rect
			(at -2.050034 -24.224996 270)
			(size 0.519938 1.4986)
			(layers "F.Cu" "F.Mask" "F.Paste")
			(net "M_H_CPU0_SA_DQ<28>")
		)
		(pad "48" smd rect
			(at -2.050034 -23.375112 270)
			(size 0.519938 1.4986)
			(layers "F.Cu" "F.Mask" "F.Paste")
			(net "GND")
		)
		(pad "49" smd rect
			(at -2.050034 -22.524974 270)
			(size 0.519938 1.4986)
			(layers "F.Cu" "F.Mask" "F.Paste")
			(net "M_H_CPU0_SA_DQ<29>")
		)
		(pad "50" smd rect
			(at -2.050034 -21.67509 270)
			(size 0.519938 1.4986)
			(layers "F.Cu" "F.Mask" "F.Paste")
			(net "GND")
		)
		(pad "51" smd rect
			(at -2.050034 -20.824952 270)
			(size 0.519938 1.4986)
			(layers "F.Cu" "F.Mask" "F.Paste")
			(net "M_H_CPU0_SA_CB<0>")
		)
		(pad "52" smd rect
			(at -2.050034 -19.975068 270)
			(size 0.519938 1.4986)
			(layers "F.Cu" "F.Mask" "F.Paste")
			(net "GND")
		)
		(pad "53" smd rect
			(at -2.050034 -19.12493 270)
			(size 0.519938 1.4986)
			(layers "F.Cu" "F.Mask" "F.Paste")
			(net "M_H_CPU0_SA_CB<1>")
		)
		(pad "54" smd rect
			(at -2.050034 -18.275046 270)
			(size 0.519938 1.4986)
			(layers "F.Cu" "F.Mask" "F.Paste")
			(net "GND")
		)
		(pad "55" smd rect
			(at -2.050034 -17.424908 270)
			(size 0.519938 1.4986)
			(layers "F.Cu" "F.Mask" "F.Paste")
			(net "M_H_CPU0_SA_DQS_DP<4>")
		)
		(pad "56" smd rect
			(at -2.050034 -16.575024 270)
			(size 0.519938 1.4986)
			(layers "F.Cu" "F.Mask" "F.Paste")
			(net "M_H_CPU0_SA_DQS_DN<4>")
		)
		(pad "57" smd rect
			(at -2.050034 -15.724886 270)
			(size 0.519938 1.4986)
			(layers "F.Cu" "F.Mask" "F.Paste")
			(net "GND")
		)
		(pad "58" smd rect
			(at -2.050034 -14.875002 270)
			(size 0.519938 1.4986)
			(layers "F.Cu" "F.Mask" "F.Paste")
			(net "M_H_CPU0_SA_CB<4>")
		)
		(pad "59" smd rect
			(at -2.050034 -14.025118 270)
			(size 0.519938 1.4986)
			(layers "F.Cu" "F.Mask" "F.Paste")
			(net "GND")
		)
		(pad "60" smd rect
			(at -2.050034 -13.17498 270)
			(size 0.519938 1.4986)
			(layers "F.Cu" "F.Mask" "F.Paste")
			(net "M_H_CPU0_SA_CB<5>")
		)
		(pad "61" smd rect
			(at -2.050034 -12.325096 270)
			(size 0.519938 1.4986)
			(layers "F.Cu" "F.Mask" "F.Paste")
			(net "GND")
		)
		(pad "62" smd rect
			(at -2.050034 -11.474958 270)
			(size 0.519938 1.4986)
			(layers "F.Cu" "F.Mask" "F.Paste")
			(net "M_H_CPU0_ALERT_N")
		)
		(pad "63" smd rect
			(at -2.050034 -10.625074 270)
			(size 0.519938 1.4986)
			(layers "F.Cu" "F.Mask" "F.Paste")
			(net "GND")
		)
		(pad "64" smd rect
			(at -2.050034 -9.774936 270)
			(size 0.519938 1.4986)
			(layers "F.Cu" "F.Mask" "F.Paste")
			(net "M_H_CPU0_SA_CS_N<2>")
		)
		(pad "65" smd rect
			(at -2.050034 -8.925052 270)
			(size 0.519938 1.4986)
			(layers "F.Cu" "F.Mask" "F.Paste")
			(net "GND")
		)
		(pad "66" smd rect
			(at -2.050034 -8.074914 270)
			(size 0.519938 1.4986)
			(layers "F.Cu" "F.Mask" "F.Paste")
			(net "M_H_CPU0_SA_CA<0>")
		)
		(pad "67" smd rect
			(at -2.050034 -7.22503 270)
			(size 0.519938 1.4986)
			(layers "F.Cu" "F.Mask" "F.Paste")
			(net "GND")
		)
		(pad "68" smd rect
			(at -2.050034 -6.374892 270)
			(size 0.519938 1.4986)
			(layers "F.Cu" "F.Mask" "F.Paste")
			(net "M_H_CPU0_SA_CA<2>")
		)
		(pad "69" smd rect
			(at -2.050034 -5.525008 270)
			(size 0.519938 1.4986)
			(layers "F.Cu" "F.Mask" "F.Paste")
			(net "GND")
		)
		(pad "70" smd rect
			(at -2.050034 -4.675124 270)
			(size 0.519938 1.4986)
			(layers "F.Cu" "F.Mask" "F.Paste")
			(net "M_H_CPU0_SA_CA<4>")
		)
		(pad "71" smd rect
			(at -2.050034 -3.824986 270)
			(size 0.519938 1.4986)
			(layers "F.Cu" "F.Mask" "F.Paste")
			(net "GND")
		)
		(pad "72" smd rect
			(at -2.050034 -2.975102 270)
			(size 0.519938 1.4986)
			(layers "F.Cu" "F.Mask" "F.Paste")
			(net "M_H_CPU0_SA_CA<6>")
		)
		(pad "73" smd rect
			(at -2.050034 -2.124964 270)
			(size 0.519938 1.4986)
			(layers "F.Cu" "F.Mask" "F.Paste")
			(net "GND")
		)
		(pad "74" smd rect
			(at -2.050034 -1.27508 270)
			(size 0.519938 1.4986)
			(layers "F.Cu" "F.Mask" "F.Paste")
			(net "M_H_CPU0_SA_PAR")
		)
		(pad "75" smd rect
			(at -2.050034 -0.424942 270)
			(size 0.519938 1.4986)
			(layers "F.Cu" "F.Mask" "F.Paste")
			(net "GND")
		)
		(pad "76" smd rect
			(at -2.050034 5.525008 270)
			(size 0.519938 1.4986)
			(layers "F.Cu" "F.Mask" "F.Paste")
			(net "M_H_CPU0_SB_CA<0>")
		)
		(pad "77" smd rect
			(at -2.050034 6.374892 270)
			(size 0.519938 1.4986)
			(layers "F.Cu" "F.Mask" "F.Paste")
			(net "GND")
		)
		(pad "78" smd rect
			(at -2.050034 7.22503 270)
			(size 0.519938 1.4986)
			(layers "F.Cu" "F.Mask" "F.Paste")
			(net "M_H_CPU0_SB_CA<2>")
		)
		(pad "79" smd rect
			(at -2.050034 8.074914 270)
			(size 0.519938 1.4986)
			(layers "F.Cu" "F.Mask" "F.Paste")
			(net "GND")
		)
		(pad "80" smd rect
			(at -2.050034 8.925052 270)
			(size 0.519938 1.4986)
			(layers "F.Cu" "F.Mask" "F.Paste")
			(net "M_H_CPU0_SB_CA<4>")
		)
		(pad "81" smd rect
			(at -2.050034 9.774936 270)
			(size 0.519938 1.4986)
			(layers "F.Cu" "F.Mask" "F.Paste")
			(net "GND")
		)
		(pad "82" smd rect
			(at -2.050034 10.625074 270)
			(size 0.519938 1.4986)
			(layers "F.Cu" "F.Mask" "F.Paste")
			(net "M_H_CPU0_SB_CA<6>")
		)
		(pad "83" smd rect
			(at -2.050034 11.474958 270)
			(size 0.519938 1.4986)
			(layers "F.Cu" "F.Mask" "F.Paste")
			(net "GND")
		)
		(pad "84" smd rect
			(at -2.050034 12.325096 270)
			(size 0.519938 1.4986)
			(layers "F.Cu" "F.Mask" "F.Paste")
			(net "M_H_CPU0_SB_CS_N<2>")
		)
		(pad "85" smd rect
			(at -2.050034 13.17498 270)
			(size 0.519938 1.4986)
			(layers "F.Cu" "F.Mask" "F.Paste")
			(net "GND")
		)
		(pad "86" smd rect
			(at -2.050034 14.025118 270)
			(size 0.519938 1.4986)
			(layers "F.Cu" "F.Mask" "F.Paste")
			(net "M_H_CPU0_SA_RSP<1>")
		)
		(pad "87" smd rect
			(at -2.050034 14.875002 270)
			(size 0.519938 1.4986)
			(layers "F.Cu" "F.Mask" "F.Paste")
			(net "M_H_CPU0_SB_RSP<1>")
		)
		(pad "88" smd rect
			(at -2.050034 15.724886 270)
			(size 0.519938 1.4986)
			(layers "F.Cu" "F.Mask" "F.Paste")
			(net "GND")
		)
		(pad "89" smd rect
			(at -2.050034 16.575024 270)
			(size 0.519938 1.4986)
			(layers "F.Cu" "F.Mask" "F.Paste")
			(net "M_H_CPU0_SB_CB<4>")
		)
		(pad "90" smd rect
			(at -2.050034 17.424908 270)
			(size 0.519938 1.4986)
			(layers "F.Cu" "F.Mask" "F.Paste")
			(net "GND")
		)
		(pad "91" smd rect
			(at -2.050034 18.275046 270)
			(size 0.519938 1.4986)
			(layers "F.Cu" "F.Mask" "F.Paste")
			(net "M_H_CPU0_SB_CB<5>")
		)
		(pad "92" smd rect
			(at -2.050034 19.12493 270)
			(size 0.519938 1.4986)
			(layers "F.Cu" "F.Mask" "F.Paste")
			(net "GND")
		)
		(pad "93" smd rect
			(at -2.050034 19.975068 270)
			(size 0.519938 1.4986)
			(layers "F.Cu" "F.Mask" "F.Paste")
			(net "M_H_CPU0_SB_DQS_DP<9>")
		)
		(pad "94" smd rect
			(at -2.050034 20.824952 270)
			(size 0.519938 1.4986)
			(layers "F.Cu" "F.Mask" "F.Paste")
			(net "M_H_CPU0_SB_DQS_DN<9>")
		)
		(pad "95" smd rect
			(at -2.050034 21.67509 270)
			(size 0.519938 1.4986)
			(layers "F.Cu" "F.Mask" "F.Paste")
			(net "GND")
		)
		(pad "96" smd rect
			(at -2.050034 22.524974 270)
			(size 0.519938 1.4986)
			(layers "F.Cu" "F.Mask" "F.Paste")
			(net "M_H_CPU0_SB_CB<0>")
		)
		(pad "97" smd rect
			(at -2.050034 23.375112 270)
			(size 0.519938 1.4986)
			(layers "F.Cu" "F.Mask" "F.Paste")
			(net "GND")
		)
		(pad "98" smd rect
			(at -2.050034 24.224996 270)
			(size 0.519938 1.4986)
			(layers "F.Cu" "F.Mask" "F.Paste")
			(net "M_H_CPU0_SB_CB<1>")
		)
		(pad "99" smd rect
			(at -2.050034 25.07488 270)
			(size 0.519938 1.4986)
			(layers "F.Cu" "F.Mask" "F.Paste")
			(net "GND")
		)
		(pad "100" smd rect
			(at -2.050034 25.925018 270)
			(size 0.519938 1.4986)
			(layers "F.Cu" "F.Mask" "F.Paste")
			(net "M_H_CPU0_SB_DQ<0>")
		)
		(pad "101" smd rect
			(at -2.050034 26.774902 270)
			(size 0.519938 1.4986)
			(layers "F.Cu" "F.Mask" "F.Paste")
			(net "GND")
		)
		(pad "102" smd rect
			(at -2.050034 27.62504 270)
			(size 0.519938 1.4986)
			(layers "F.Cu" "F.Mask" "F.Paste")
			(net "M_H_CPU0_SB_DQ<1>")
		)
		(pad "103" smd rect
			(at -2.050034 28.474924 270)
			(size 0.519938 1.4986)
			(layers "F.Cu" "F.Mask" "F.Paste")
			(net "GND")
		)
		(pad "104" smd rect
			(at -2.050034 29.325062 270)
			(size 0.519938 1.4986)
			(layers "F.Cu" "F.Mask" "F.Paste")
			(net "M_H_CPU0_SB_DQS_DP<0>")
		)
		(pad "105" smd rect
			(at -2.050034 30.174946 270)
			(size 0.519938 1.4986)
			(layers "F.Cu" "F.Mask" "F.Paste")
			(net "M_H_CPU0_SB_DQS_DN<0>")
		)
		(pad "106" smd rect
			(at -2.050034 31.025084 270)
			(size 0.519938 1.4986)
			(layers "F.Cu" "F.Mask" "F.Paste")
			(net "GND")
		)
		(pad "107" smd rect
			(at -2.050034 31.874968 270)
			(size 0.519938 1.4986)
			(layers "F.Cu" "F.Mask" "F.Paste")
			(net "M_H_CPU0_SB_DQ<4>")
		)
		(pad "108" smd rect
			(at -2.050034 32.725106 270)
			(size 0.519938 1.4986)
			(layers "F.Cu" "F.Mask" "F.Paste")
			(net "GND")
		)
		(pad "109" smd rect
			(at -2.050034 33.57499 270)
			(size 0.519938 1.4986)
			(layers "F.Cu" "F.Mask" "F.Paste")
			(net "M_H_CPU0_SB_DQ<5>")
		)
		(pad "110" smd rect
			(at -2.050034 34.425128 270)
			(size 0.519938 1.4986)
			(layers "F.Cu" "F.Mask" "F.Paste")
			(net "GND")
		)
		(pad "111" smd rect
			(at -2.050034 35.275012 270)
			(size 0.519938 1.4986)
			(layers "F.Cu" "F.Mask" "F.Paste")
			(net "M_H_CPU0_SB_DQ<8>")
		)
		(pad "112" smd rect
			(at -2.050034 36.124896 270)
			(size 0.519938 1.4986)
			(layers "F.Cu" "F.Mask" "F.Paste")
			(net "GND")
		)
	)
)
